# S9S_MB_2U (Grand Teton) — schematic netlist excerpt (pin names and nets, part order shuffled) for the footprints in the layout excerpt that follows; sources: Cadence DE-HDL packaged netlist, KiCad conversion of 03242023_DA0F0TMBIJ0_F0T_Motherboard_J_brd_V01_OCP.brd

PR400  Q_RES  10K 1% EMPTY  pkg 0402LF  page 266 : A = PVCCIN_CPU0_ATSEN ; B = GND
C311  Q_CAP  47UF 4V 20% X6S  pkg C0805  page 78 : A = PVCCIN_CPU1 ; B = GND
R1237  Q_RES  240 1% EMPTY  pkg 0402LF  page 119 : A = GND ; B = PD_EXT_CLK_SEL_CPU0

(kicad_pcb
	(version 20260206)
	(generator "pcbnew")
	(generator_version "10.0")
	(general
		(thickness 1.6)
		(legacy_teardrops no)
	)
	(paper "A4")
	(title_block
		(title "03242023_DA0F0TMBIJ0_F0T_Motherboard_J_brd_V01_OCP.brd")
		(comment 1 "Grand Teton / footprints 4894-4896 of 6105")
	)
	(layers
		(0 "F.Cu" signal "TOP")
		(4 "In1.Cu" signal "GND")
		(6 "In2.Cu" signal "IN1")
		(8 "In3.Cu" signal "GND1")
		(10 "In4.Cu" signal "IN2")
		(12 "In5.Cu" signal "GND2")
		(14 "In6.Cu" signal "IN3")
		(16 "In7.Cu" signal "GND3")
		(18 "In8.Cu" signal "VCC")
		(20 "In9.Cu" signal "VCC1")
		(22 "In10.Cu" signal "GND4")
		(24 "In11.Cu" signal "IN4")
		(26 "In12.Cu" signal "GND5")
		(28 "In13.Cu" signal "IN5")
		(30 "In14.Cu" signal "GND6")
		(32 "In15.Cu" signal "IN6")
		(34 "In16.Cu" signal "GND7")
		(2 "B.Cu" signal "BOTTOM")
		(9 "F.Adhes" user "F.Adhesive")
		(11 "B.Adhes" user "B.Adhesive")
		(13 "F.Paste" user "Package Geometry/Pastemask Top")
		(15 "B.Paste" user "Package Geometry/Pastemask Bottom")
		(5 "F.SilkS" user "Ref Des/Silkscreen Top")
		(7 "B.SilkS" user "Ref Des/Silkscreen Bottom")
		(1 "F.Mask" user "Board Geometry/Soldermask Top")
		(3 "B.Mask" user "Board Geometry/Soldermask Bottom")
		(17 "Dwgs.User" user "User.Drawings")
		(19 "Cmts.User" user "User.Comments")
		(21 "Eco1.User" user "User.Eco1")
		(23 "Eco2.User" user "User.Eco2")
		(25 "Edge.Cuts" user "Board Geometry/Outline")
		(27 "Margin" user)
		(31 "F.CrtYd" user "Package Geometry/Place Bound Top")
		(29 "B.CrtYd" user "Package Geometry/Place Bound Bottom")
		(35 "F.Fab" user "Ref Des/Assembly Top")
		(33 "B.Fab" user "Ref Des/Assembly Bottom")
	)
	(footprint ""
		(layer "B.Cu")
		(at 116.40312 -241.14252 -90)
		(property "Reference" "C311"
			(at 0 0 90)
			(layer "B.SilkS")
			(hide yes)
			(effects
				(font
					(size 1.27 1.27)
				)
				(justify mirror)
			)
		)
		(property "Value" ""
			(at 0 0 90)
			(layer "B.Fab")
			(effects
				(font
					(size 1.27 1.27)
				)
				(justify mirror)
			)
		)
		(duplicate_pad_numbers_are_jumpers no)
		(fp_line
			(start -1.524 0.762)
			(end 1.524 0.762)
			(stroke
				(width 0.1524)
				(type default)
			)
			(layer "B.SilkS")
		)
		(fp_line
			(start 1.524 0.762)
			(end 1.524 -0.762)
			(stroke
				(width 0.1524)
				(type default)
			)
			(layer "B.SilkS")
		)
		(fp_line
			(start -1.524 -0.762)
			(end -1.524 0.762)
			(stroke
				(width 0.1524)
				(type default)
			)
			(layer "B.SilkS")
		)
		(fp_line
			(start 1.524 -0.762)
			(end -1.524 -0.762)
			(stroke
				(width 0.1524)
				(type default)
			)
			(layer "B.SilkS")
		)
		(fp_line
			(start -1.1049 0.724916)
			(end -1.1049 -0.724916)
			(stroke
				(width 0.1)
				(type default)
			)
			(layer "B.Fab")
		)
		(fp_line
			(start 1.1049 0.724916)
			(end -1.1049 0.724916)
			(stroke
				(width 0.1)
				(type default)
			)
			(layer "B.Fab")
		)
		(fp_line
			(start -1.1049 -0.724916)
			(end 1.1049 -0.724916)
			(stroke
				(width 0.1)
				(type default)
			)
			(layer "B.Fab")
		)
		(fp_line
			(start 1.1049 -0.724916)
			(end 1.1049 0.724916)
			(stroke
				(width 0.1)
				(type default)
			)
			(layer "B.Fab")
		)
		(pad "1" smd rect
			(at 0.889 0 270)
			(size 1.016 1.27)
			(layers "B.Cu" "B.Mask" "B.Paste")
			(net "PVCCIN_CPU1")
		)
		(pad "2" smd rect
			(at -0.889 0 270)
			(size 1.016 1.27)
			(layers "B.Cu" "B.Mask" "B.Paste")
			(net "GND")
		)
	)
	(footprint ""
		(layer "B.Cu")
		(at 339.97773 -190.703454 90)
		(property "Reference" "R1237"
			(at 0 0 90)
			(layer "B.SilkS")
			(hide yes)
			(effects
				(font
					(size 1.27 1.27)
				)
				(justify mirror)
			)
		)
		(property "Value" ""
			(at 0 0 90)
			(layer "B.Fab")
			(effects
				(font
					(size 1.27 1.27)
				)
				(justify mirror)
			)
		)
		(duplicate_pad_numbers_are_jumpers no)
		(fp_line
			(start 0.7874 -0.4064)
			(end -0.7874 -0.4064)
			(stroke
				(width 0.1524)
				(type default)
			)
			(layer "B.SilkS")
		)
		(fp_line
			(start -0.7874 -0.4064)
			(end -0.7874 0.4064)
			(stroke
				(width 0.1524)
				(type default)
			)
			(layer "B.SilkS")
		)
		(fp_line
			(start 0.7874 0.4064)
			(end 0.7874 -0.4064)
			(stroke
				(width 0.1524)
				(type default)
			)
			(layer "B.SilkS")
		)
		(fp_line
			(start -0.7874 0.4064)
			(end 0.7874 0.4064)
			(stroke
				(width 0.1524)
				(type default)
			)
			(layer "B.SilkS")
		)
		(fp_line
			(start 0.67945 -0.305054)
			(end 0.12065 -0.305054)
			(stroke
				(width 0.1)
				(type default)
			)
			(layer "B.Fab")
		)
		(fp_line
			(start 0.12065 -0.305054)
			(end 0.12065 -0.2794)
			(stroke
				(width 0.1)
				(type default)
			)
			(layer "B.Fab")
		)
		(fp_line
			(start -0.12065 -0.3048)
			(end -0.67945 -0.3048)
			(stroke
				(width 0.1)
				(type default)
			)
			(layer "B.Fab")
		)
		(fp_line
			(start -0.67945 -0.3048)
			(end -0.67945 0.3048)
			(stroke
				(width 0.1)
				(type default)
			)
			(layer "B.Fab")
		)
		(fp_line
			(start 0.12065 -0.2794)
			(end -0.12065 -0.2794)
			(stroke
				(width 0.1)
				(type default)
			)
			(layer "B.Fab")
		)
		(fp_line
			(start -0.12065 -0.2794)
			(end -0.12065 -0.3048)
			(stroke
				(width 0.1)
				(type default)
			)
			(layer "B.Fab")
		)
		(fp_line
			(start 0.12065 0.2794)
			(end 0.12065 0.3048)
			(stroke
				(width 0.1)
				(type default)
			)
			(layer "B.Fab")
		)
		(fp_line
			(start -0.120396 0.2794)
			(end 0.12065 0.2794)
			(stroke
				(width 0.1)
				(type default)
			)
			(layer "B.Fab")
		)
		(fp_line
			(start 0.67945 0.3048)
			(end 0.67945 -0.305054)
			(stroke
				(width 0.1)
				(type default)
			)
			(layer "B.Fab")
		)
		(fp_line
			(start 0.12065 0.3048)
			(end 0.67945 0.3048)
			(stroke
				(width 0.1)
				(type default)
			)
			(layer "B.Fab")
		)
		(fp_line
			(start -0.120396 0.3048)
			(end -0.120396 0.2794)
			(stroke
				(width 0.1)
				(type default)
			)
			(layer "B.Fab")
		)
		(fp_line
			(start -0.67945 0.3048)
			(end -0.120396 0.3048)
			(stroke
				(width 0.1)
				(type default)
			)
			(layer "B.Fab")
		)
		(pad "1" smd circle
			(at 0.40005 0 270)
			(size 0 0)
			(layers "B.Cu" "B.Mask" "B.Paste")
			(net "GND")
		)
		(pad "2" smd circle
			(at -0.40005 0 270)
			(size 0 0)
			(layers "B.Cu" "B.Mask" "B.Paste")
			(net "PD_EXT_CLK_SEL_CPU0")
		)
	)
	(footprint ""
		(layer "B.Cu")
		(at 362.629704 -358.675432 180)
		(property "Reference" "PR400"
			(at 0 0 0)
			(layer "B.SilkS")
			(hide yes)
			(effects
				(font
					(size 1.27 1.27)
				)
				(justify mirror)
			)
		)
		(property "Value" ""
			(at 0 0 0)
			(layer "B.Fab")
			(effects
				(font
					(size 1.27 1.27)
				)
				(justify mirror)
			)
		)
		(duplicate_pad_numbers_are_jumpers no)
		(fp_line
			(start 0.7874 0.4064)
			(end 0.7874 -0.4064)
			(stroke
				(width 0.1524)
				(type default)
			)
			(layer "B.SilkS")
		)
		(fp_line
			(start 0.7874 -0.4064)
			(end -0.7874 -0.4064)
			(stroke
				(width 0.1524)
				(type default)
			)
			(layer "B.SilkS")
		)
		(fp_line
			(start -0.7874 0.4064)
			(end 0.7874 0.4064)
			(stroke
				(width 0.1524)
				(type default)
			)
			(layer "B.SilkS")
		)
		(fp_line
			(start -0.7874 -0.4064)
			(end -0.7874 0.4064)
			(stroke
				(width 0.1524)
				(type default)
			)
			(layer "B.SilkS")
		)
		(fp_line
			(start 0.67945 0.3048)
			(end 0.67945 -0.305054)
			(stroke
				(width 0.1)
				(type default)
			)
			(layer "B.Fab")
		)
		(fp_line
			(start 0.67945 -0.305054)
			(end 0.12065 -0.305054)
			(stroke
				(width 0.1)
				(type default)
			)
			(layer "B.Fab")
		)
		(fp_line
			(start 0.12065 0.3048)
			(end 0.67945 0.3048)
			(stroke
				(width 0.1)
				(type default)
			)
			(layer "B.Fab")
		)
		(fp_line
			(start 0.12065 0.2794)
			(end 0.12065 0.3048)
			(stroke
				(width 0.1)
				(type default)
			)
			(layer "B.Fab")
		)
		(fp_line
			(start 0.12065 -0.2794)
			(end -0.12065 -0.2794)
			(stroke
				(width 0.1)
				(type default)
			)
			(layer "B.Fab")
		)
		(fp_line
			(start 0.12065 -0.305054)
			(end 0.12065 -0.2794)
			(stroke
				(width 0.1)
				(type default)
			)
			(layer "B.Fab")
		)
		(fp_line
			(start -0.120396 0.3048)
			(end -0.120396 0.2794)
			(stroke
				(width 0.1)
				(type default)
			)
			(layer "B.Fab")
		)
		(fp_line
			(start -0.120396 0.2794)
			(end 0.12065 0.2794)
			(stroke
				(width 0.1)
				(type default)
			)
			(layer "B.Fab")
		)
		(fp_line
			(start -0.12065 -0.2794)
			(end -0.12065 -0.3048)
			(stroke
				(width 0.1)
				(type default)
			)
			(layer "B.Fab")
		)
		(fp_line
			(start -0.12065 -0.3048)
			(end -0.67945 -0.3048)
			(stroke
				(width 0.1)
				(type default)
			)
			(layer "B.Fab")
		)
		(fp_line
			(start -0.67945 0.3048)
			(end -0.120396 0.3048)
			(stroke
				(width 0.1)
				(type default)
			)
			(layer "B.Fab")
		)
		(fp_line
			(start -0.67945 -0.3048)
			(end -0.67945 0.3048)
			(stroke
				(width 0.1)
				(type default)
			)
			(layer "B.Fab")
		)
		(pad "1" smd circle
			(at 0.40005 0)
			(size 0 0)
			(layers "B.Cu" "B.Mask" "B.Paste")
			(net "PVCCIN_CPU0_ATSEN")
		)
		(pad "2" smd circle
			(at -0.40005 0)
			(size 0 0)
			(layers "B.Cu" "B.Mask" "B.Paste")
			(net "GND")
		)
	)
)
